(kicad_pcb
	(version 20260206)
	(generator "pcbnew")
	(generator_version "10.0")
	(general
		(thickness 1.6)
		(legacy_teardrops no)
	)
	(paper "A4")
	(title_block
		(title "04192023_DAF0TMB3IC0_F0TG_MB_C_brd_V02_OCP.brd")
		(comment 1 "Grand Teton / footprints 43-48 of 8354")
	)
	(layers
		(0 "F.Cu" signal "TOP")
		(4 "In1.Cu" signal "GND")
		(6 "In2.Cu" signal "IN1")
		(8 "In3.Cu" signal "GND1")
		(10 "In4.Cu" signal "IN2")
		(12 "In5.Cu" signal "GND2")
		(14 "In6.Cu" signal "IN3")
		(16 "In7.Cu" signal "GND3")
		(18 "In8.Cu" signal "VCC")
		(20 "In9.Cu" signal "VCC1")
		(22 "In10.Cu" signal "GND4")
		(24 "In11.Cu" signal "IN4")
		(26 "In12.Cu" signal "GND5")
		(28 "In13.Cu" signal "IN5")
		(30 "In14.Cu" signal "GND6")
		(32 "In15.Cu" signal "IN6")
		(34 "In16.Cu" signal "GND7")
		(2 "B.Cu" signal "BOTTOM")
		(9 "F.Adhes" user "F.Adhesive")
		(11 "B.Adhes" user "B.Adhesive")
		(13 "F.Paste" user "Package Geometry/Pastemask Top")
		(15 "B.Paste" user "Package Geometry/Pastemask Bottom")
		(5 "F.SilkS" user "Ref Des/Silkscreen Top")
		(7 "B.SilkS" user "Ref Des/Silkscreen Bottom")
		(1 "F.Mask" user "Board Geometry/Soldermask Top")
		(3 "B.Mask" user "Board Geometry/Soldermask Bottom")
		(17 "Dwgs.User" user "User.Drawings")
		(19 "Cmts.User" user "User.Comments")
		(21 "Eco1.User" user "User.Eco1")
		(23 "Eco2.User" user "User.Eco2")
		(25 "Edge.Cuts" user "Board Geometry/Outline")
		(27 "Margin" user)
		(31 "F.CrtYd" user "Package Geometry/Place Bound Top")
		(29 "B.CrtYd" user "Package Geometry/Place Bound Bottom")
		(35 "F.Fab" user "Ref Des/Assembly Top")
		(33 "B.Fab" user "Ref Des/Assembly Bottom")
	)
	(footprint ""
		(layer "F.Cu")
		(at 277.352252 -119.91467 180)
		(property "Reference" "R6201"
			(at 0 0 180)
			(layer "F.SilkS")
			(hide yes)
			(effects
				(font
					(size 1.27 1.27)
				)
			)
		)
		(property "Value" ""
			(at 0 0 180)
			(layer "F.Fab")
			(effects
				(font
					(size 1.27 1.27)
				)
			)
		)
		(duplicate_pad_numbers_are_jumpers no)
		(fp_line
			(start 0.7874 0.4064)
			(end -0.7874 0.4064)
			(stroke
				(width 0.1524)
				(type default)
			)
			(layer "F.SilkS")
		)
		(fp_line
			(start 0.7874 -0.4064)
			(end 0.7874 0.4064)
			(stroke
				(width 0.1524)
				(type default)
			)
			(layer "F.SilkS")
		)
		(fp_line
			(start -0.7874 0.4064)
			(end -0.7874 -0.4064)
			(stroke
				(width 0.1524)
				(type default)
			)
			(layer "F.SilkS")
		)
		(fp_line
			(start -0.7874 -0.4064)
			(end 0.7874 -0.4064)
			(stroke
				(width 0.1524)
				(type default)
			)
			(layer "F.SilkS")
		)
		(fp_line
			(start 0.67945 0.3048)
			(end 0.120396 0.3048)
			(stroke
				(width 0.1)
				(type default)
			)
			(layer "F.Fab")
		)
		(fp_line
			(start 0.67945 -0.3048)
			(end 0.67945 0.3048)
			(stroke
				(width 0.1)
				(type default)
			)
			(layer "F.Fab")
		)
		(fp_line
			(start 0.12065 -0.2794)
			(end 0.12065 -0.3048)
			(stroke
				(width 0.1)
				(type default)
			)
			(layer "F.Fab")
		)
		(fp_line
			(start 0.12065 -0.3048)
			(end 0.67945 -0.3048)
			(stroke
				(width 0.1)
				(type default)
			)
			(layer "F.Fab")
		)
		(fp_line
			(start 0.120396 0.3048)
			(end 0.120396 0.2794)
			(stroke
				(width 0.1)
				(type default)
			)
			(layer "F.Fab")
		)
		(fp_line
			(start 0.120396 0.2794)
			(end -0.12065 0.2794)
			(stroke
				(width 0.1)
				(type default)
			)
			(layer "F.Fab")
		)
		(fp_line
			(start -0.12065 0.3048)
			(end -0.67945 0.3048)
			(stroke
				(width 0.1)
				(type default)
			)
			(layer "F.Fab")
		)
		(fp_line
			(start -0.12065 0.2794)
			(end -0.12065 0.3048)
			(stroke
				(width 0.1)
				(type default)
			)
			(layer "F.Fab")
		)
		(fp_line
			(start -0.12065 -0.2794)
			(end 0.12065 -0.2794)
			(stroke
				(width 0.1)
				(type default)
			)
			(layer "F.Fab")
		)
		(fp_line
			(start -0.12065 -0.305054)
			(end -0.12065 -0.2794)
			(stroke
				(width 0.1)
				(type default)
			)
			(layer "F.Fab")
		)
		(fp_line
			(start -0.67945 0.3048)
			(end -0.67945 -0.305054)
			(stroke
				(width 0.1)
				(type default)
			)
			(layer "F.Fab")
		)
		(fp_line
			(start -0.67945 -0.305054)
			(end -0.12065 -0.305054)
			(stroke
				(width 0.1)
				(type default)
			)
			(layer "F.Fab")
		)
		(pad "1" smd circle
			(at -0.40005 0 180)
			(size 0 0)
			(layers "F.Cu" "F.Mask" "F.Paste")
			(net "SMB_USB_CPU0_HUB1_SCL_R")
		)
		(pad "2" smd circle
			(at 0.40005 0 180)
			(size 0 0)
			(layers "F.Cu" "F.Mask" "F.Paste")
			(net "SMB_USB_CPU0_HUB1_SCL")
		)
	)
	(footprint ""
		(layer "F.Cu")
		(at 26.954734 -394.733526 180)
		(property "Reference" "PC6633_2"
			(at 0 0 180)
			(layer "F.SilkS")
			(hide yes)
			(effects
				(font
					(size 1.27 1.27)
				)
			)
		)
		(property "Value" ""
			(at 0 0 180)
			(layer "F.Fab")
			(effects
				(font
					(size 1.27 1.27)
				)
			)
		)
		(duplicate_pad_numbers_are_jumpers no)
		(fp_line
			(start 0.7874 0.4064)
			(end -0.7874 0.4064)
			(stroke
				(width 0.1524)
				(type default)
			)
			(layer "F.SilkS")
		)
		(fp_line
			(start 0.7874 -0.4064)
			(end 0.7874 0.4064)
			(stroke
				(width 0.1524)
				(type default)
			)
			(layer "F.SilkS")
		)
		(fp_line
			(start -0.7874 0.4064)
			(end -0.7874 -0.4064)
			(stroke
				(width 0.1524)
				(type default)
			)
			(layer "F.SilkS")
		)
		(fp_line
			(start -0.7874 -0.4064)
			(end 0.7874 -0.4064)
			(stroke
				(width 0.1524)
				(type default)
			)
			(layer "F.SilkS")
		)
		(fp_line
			(start 0.67945 0.3048)
			(end 0.120396 0.3048)
			(stroke
				(width 0.1)
				(type default)
			)
			(layer "F.Fab")
		)
		(fp_line
			(start 0.67945 -0.3048)
			(end 0.67945 0.3048)
			(stroke
				(width 0.1)
				(type default)
			)
			(layer "F.Fab")
		)
		(fp_line
			(start 0.12065 -0.2794)
			(end 0.12065 -0.3048)
			(stroke
				(width 0.1)
				(type default)
			)
			(layer "F.Fab")
		)
		(fp_line
			(start 0.12065 -0.3048)
			(end 0.67945 -0.3048)
			(stroke
				(width 0.1)
				(type default)
			)
			(layer "F.Fab")
		)
		(fp_line
			(start 0.120396 0.3048)
			(end 0.120396 0.2794)
			(stroke
				(width 0.1)
				(type default)
			)
			(layer "F.Fab")
		)
		(fp_line
			(start 0.120396 0.2794)
			(end -0.12065 0.2794)
			(stroke
				(width 0.1)
				(type default)
			)
			(layer "F.Fab")
		)
		(fp_line
			(start -0.12065 0.3048)
			(end -0.67945 0.3048)
			(stroke
				(width 0.1)
				(type default)
			)
			(layer "F.Fab")
		)
		(fp_line
			(start -0.12065 0.2794)
			(end -0.12065 0.3048)
			(stroke
				(width 0.1)
				(type default)
			)
			(layer "F.Fab")
		)
		(fp_line
			(start -0.12065 -0.2794)
			(end 0.12065 -0.2794)
			(stroke
				(width 0.1)
				(type default)
			)
			(layer "F.Fab")
		)
		(fp_line
			(start -0.12065 -0.305054)
			(end -0.12065 -0.2794)
			(stroke
				(width 0.1)
				(type default)
			)
			(layer "F.Fab")
		)
		(fp_line
			(start -0.67945 0.3048)
			(end -0.67945 -0.305054)
			(stroke
				(width 0.1)
				(type default)
			)
			(layer "F.Fab")
		)
		(fp_line
			(start -0.67945 -0.305054)
			(end -0.12065 -0.305054)
			(stroke
				(width 0.1)
				(type default)
			)
			(layer "F.Fab")
		)
		(pad "1" smd circle
			(at -0.40005 0 180)
			(size 0 0)
			(layers "F.Cu" "F.Mask" "F.Paste")
			(net "SW_P12V_AUX_P0V9_RETIMER_CPU1_FLT")
		)
		(pad "2" smd circle
			(at 0.40005 0 180)
			(size 0 0)
			(layers "F.Cu" "F.Mask" "F.Paste")
			(net "GND")
		)
	)
	(footprint ""
		(layer "F.Cu")
		(at 118.491 -421.513)
		(property "Reference" "R3436"
			(at 0 0 0)
			(layer "F.SilkS")
			(hide yes)
			(effects
				(font
					(size 1.27 1.27)
				)
			)
		)
		(property "Value" ""
			(at 0 0 0)
			(layer "F.Fab")
			(effects
				(font
					(size 1.27 1.27)
				)
			)
		)
		(duplicate_pad_numbers_are_jumpers no)
		(fp_line
			(start -0.7874 -0.4064)
			(end 0.7874 -0.4064)
			(stroke
				(width 0.1524)
				(type default)
			)
			(layer "F.SilkS")
		)
		(fp_line
			(start -0.7874 0.4064)
			(end -0.7874 -0.4064)
			(stroke
				(width 0.1524)
				(type default)
			)
			(layer "F.SilkS")
		)
		(fp_line
			(start 0.7874 -0.4064)
			(end 0.7874 0.4064)
			(stroke
				(width 0.1524)
				(type default)
			)
			(layer "F.SilkS")
		)
		(fp_line
			(start 0.7874 0.4064)
			(end -0.7874 0.4064)
			(stroke
				(width 0.1524)
				(type default)
			)
			(layer "F.SilkS")
		)
		(fp_line
			(start -0.67945 -0.305054)
			(end -0.12065 -0.305054)
			(stroke
				(width 0.1)
				(type default)
			)
			(layer "F.Fab")
		)
		(fp_line
			(start -0.67945 0.3048)
			(end -0.67945 -0.305054)
			(stroke
				(width 0.1)
				(type default)
			)
			(layer "F.Fab")
		)
		(fp_line
			(start -0.12065 -0.305054)
			(end -0.12065 -0.2794)
			(stroke
				(width 0.1)
				(type default)
			)
			(layer "F.Fab")
		)
		(fp_line
			(start -0.12065 -0.2794)
			(end 0.12065 -0.2794)
			(stroke
				(width 0.1)
				(type default)
			)
			(layer "F.Fab")
		)
		(fp_line
			(start -0.12065 0.2794)
			(end -0.12065 0.3048)
			(stroke
				(width 0.1)
				(type default)
			)
			(layer "F.Fab")
		)
		(fp_line
			(start -0.12065 0.3048)
			(end -0.67945 0.3048)
			(stroke
				(width 0.1)
				(type default)
			)
			(layer "F.Fab")
		)
		(fp_line
			(start 0.120396 0.2794)
			(end -0.12065 0.2794)
			(stroke
				(width 0.1)
				(type default)
			)
			(layer "F.Fab")
		)
		(fp_line
			(start 0.120396 0.3048)
			(end 0.120396 0.2794)
			(stroke
				(width 0.1)
				(type default)
			)
			(layer "F.Fab")
		)
		(fp_line
			(start 0.12065 -0.3048)
			(end 0.67945 -0.3048)
			(stroke
				(width 0.1)
				(type default)
			)
			(layer "F.Fab")
		)
		(fp_line
			(start 0.12065 -0.2794)
			(end 0.12065 -0.3048)
			(stroke
				(width 0.1)
				(type default)
			)
			(layer "F.Fab")
		)
		(fp_line
			(start 0.67945 -0.3048)
			(end 0.67945 0.3048)
			(stroke
				(width 0.1)
				(type default)
			)
			(layer "F.Fab")
		)
		(fp_line
			(start 0.67945 0.3048)
			(end 0.120396 0.3048)
			(stroke
				(width 0.1)
				(type default)
			)
			(layer "F.Fab")
		)
		(pad "1" smd circle
			(at -0.40005 0)
			(size 0 0)
			(layers "F.Cu" "F.Mask" "F.Paste")
			(net "P3V3_AUX")
		)
		(pad "2" smd circle
			(at 0.40005 0)
			(size 0 0)
			(layers "F.Cu" "F.Mask" "F.Paste")
			(net "GPU_HMC_PRSNT_ISO_N")
		)
	)
	(footprint ""
		(layer "F.Cu")
		(at 88.177878 -148.94941 180)
		(property "Reference" "C295"
			(at 0 0 180)
			(layer "F.SilkS")
			(hide yes)
			(effects
				(font
					(size 1.27 1.27)
				)
			)
		)
		(property "Value" ""
			(at 0 0 180)
			(layer "F.Fab")
			(effects
				(font
					(size 1.27 1.27)
				)
			)
		)
		(duplicate_pad_numbers_are_jumpers no)
		(fp_line
			(start 0.7874 0.4064)
			(end -0.7874 0.4064)
			(stroke
				(width 0.1524)
				(type default)
			)
			(layer "F.SilkS")
		)
		(fp_line
			(start 0.7874 -0.4064)
			(end 0.7874 0.4064)
			(stroke
				(width 0.1524)
				(type default)
			)
			(layer "F.SilkS")
		)
		(fp_line
			(start -0.7874 0.4064)
			(end -0.7874 -0.4064)
			(stroke
				(width 0.1524)
				(type default)
			)
			(layer "F.SilkS")
		)
		(fp_line
			(start -0.7874 -0.4064)
			(end 0.7874 -0.4064)
			(stroke
				(width 0.1524)
				(type default)
			)
			(layer "F.SilkS")
		)
		(fp_line
			(start 0.67945 0.3048)
			(end 0.120396 0.3048)
			(stroke
				(width 0.1)
				(type default)
			)
			(layer "F.Fab")
		)
		(fp_line
			(start 0.67945 -0.3048)
			(end 0.67945 0.3048)
			(stroke
				(width 0.1)
				(type default)
			)
			(layer "F.Fab")
		)
		(fp_line
			(start 0.12065 -0.2794)
			(end 0.12065 -0.3048)
			(stroke
				(width 0.1)
				(type default)
			)
			(layer "F.Fab")
		)
		(fp_line
			(start 0.12065 -0.3048)
			(end 0.67945 -0.3048)
			(stroke
				(width 0.1)
				(type default)
			)
			(layer "F.Fab")
		)
		(fp_line
			(start 0.120396 0.3048)
			(end 0.120396 0.2794)
			(stroke
				(width 0.1)
				(type default)
			)
			(layer "F.Fab")
		)
		(fp_line
			(start 0.120396 0.2794)
			(end -0.12065 0.2794)
			(stroke
				(width 0.1)
				(type default)
			)
			(layer "F.Fab")
		)
		(fp_line
			(start -0.12065 0.3048)
			(end -0.67945 0.3048)
			(stroke
				(width 0.1)
				(type default)
			)
			(layer "F.Fab")
		)
		(fp_line
			(start -0.12065 0.2794)
			(end -0.12065 0.3048)
			(stroke
				(width 0.1)
				(type default)
			)
			(layer "F.Fab")
		)
		(fp_line
			(start -0.12065 -0.2794)
			(end 0.12065 -0.2794)
			(stroke
				(width 0.1)
				(type default)
			)
			(layer "F.Fab")
		)
		(fp_line
			(start -0.12065 -0.305054)
			(end -0.12065 -0.2794)
			(stroke
				(width 0.1)
				(type default)
			)
			(layer "F.Fab")
		)
		(fp_line
			(start -0.67945 0.3048)
			(end -0.67945 -0.305054)
			(stroke
				(width 0.1)
				(type default)
			)
			(layer "F.Fab")
		)
		(fp_line
			(start -0.67945 -0.305054)
			(end -0.12065 -0.305054)
			(stroke
				(width 0.1)
				(type default)
			)
			(layer "F.Fab")
		)
		(pad "1" smd circle
			(at -0.40005 0 180)
			(size 0 0)
			(layers "F.Cu" "F.Mask" "F.Paste")
			(net "SVID_PVDDCR_CPU0_P1_SVTO")
		)
		(pad "2" smd circle
			(at 0.40005 0 180)
			(size 0 0)
			(layers "F.Cu" "F.Mask" "F.Paste")
			(net "GND")
		)
	)
	(footprint ""
		(layer "F.Cu")
		(at 176.855882 -137.740898 -90)
		(property "Reference" "R6853"
			(at 0 0 270)
			(layer "F.SilkS")
			(hide yes)
			(effects
				(font
					(size 1.27 1.27)
				)
			)
		)
		(property "Value" ""
			(at 0 0 270)
			(layer "F.Fab")
			(effects
				(font
					(size 1.27 1.27)
				)
			)
		)
		(duplicate_pad_numbers_are_jumpers no)
		(fp_line
			(start -0.7874 0.4064)
			(end -0.7874 -0.4064)
			(stroke
				(width 0.1524)
				(type default)
			)
			(layer "F.SilkS")
		)
		(fp_line
			(start 0.7874 0.4064)
			(end -0.7874 0.4064)
			(stroke
				(width 0.1524)
				(type default)
			)
			(layer "F.SilkS")
		)
		(fp_line
			(start -0.7874 -0.4064)
			(end 0.7874 -0.4064)
			(stroke
				(width 0.1524)
				(type default)
			)
			(layer "F.SilkS")
		)
		(fp_line
			(start 0.7874 -0.4064)
			(end 0.7874 0.4064)
			(stroke
				(width 0.1524)
				(type default)
			)
			(layer "F.SilkS")
		)
		(fp_line
			(start -0.67945 0.3048)
			(end -0.67945 -0.305054)
			(stroke
				(width 0.1)
				(type default)
			)
			(layer "F.Fab")
		)
		(fp_line
			(start -0.12065 0.3048)
			(end -0.67945 0.3048)
			(stroke
				(width 0.1)
				(type default)
			)
			(layer "F.Fab")
		)
		(fp_line
			(start 0.120396 0.3048)
			(end 0.120396 0.2794)
			(stroke
				(width 0.1)
				(type default)
			)
			(layer "F.Fab")
		)
		(fp_line
			(start 0.67945 0.3048)
			(end 0.120396 0.3048)
			(stroke
				(width 0.1)
				(type default)
			)
			(layer "F.Fab")
		)
		(fp_line
			(start -0.12065 0.2794)
			(end -0.12065 0.3048)
			(stroke
				(width 0.1)
				(type default)
			)
			(layer "F.Fab")
		)
		(fp_line
			(start 0.120396 0.2794)
			(end -0.12065 0.2794)
			(stroke
				(width 0.1)
				(type default)
			)
			(layer "F.Fab")
		)
		(fp_line
			(start -0.12065 -0.2794)
			(end 0.12065 -0.2794)
			(stroke
				(width 0.1)
				(type default)
			)
			(layer "F.Fab")
		)
		(fp_line
			(start 0.12065 -0.2794)
			(end 0.12065 -0.3048)
			(stroke
				(width 0.1)
				(type default)
			)
			(layer "F.Fab")
		)
		(fp_line
			(start 0.12065 -0.3048)
			(end 0.67945 -0.3048)
			(stroke
				(width 0.1)
				(type default)
			)
			(layer "F.Fab")
		)
		(fp_line
			(start 0.67945 -0.3048)
			(end 0.67945 0.3048)
			(stroke
				(width 0.1)
				(type default)
			)
			(layer "F.Fab")
		)
		(fp_line
			(start -0.67945 -0.305054)
			(end -0.12065 -0.305054)
			(stroke
				(width 0.1)
				(type default)
			)
			(layer "F.Fab")
		)
		(fp_line
			(start -0.12065 -0.305054)
			(end -0.12065 -0.2794)
			(stroke
				(width 0.1)
				(type default)
			)
			(layer "F.Fab")
		)
		(pad "1" smd circle
			(at -0.40005 0 270)
			(size 0 0)
			(layers "F.Cu" "F.Mask" "F.Paste")
			(net "PWRGD_P0V9_RETIMER_CPU1")
		)
		(pad "2" smd circle
			(at 0.40005 0 270)
			(size 0 0)
			(layers "F.Cu" "F.Mask" "F.Paste")
			(net "PWRGD_P0V9_RETIMER_CPU1_R2")
		)
	)
	(footprint ""
		(layer "F.Cu")
		(at 143.96339 -31.18739 180)
		(property "Reference" "R342"
			(at 0 0 180)
			(layer "F.SilkS")
			(hide yes)
			(effects
				(font
					(size 1.27 1.27)
				)
			)
		)
		(property "Value" ""
			(at 0 0 180)
			(layer "F.Fab")
			(effects
				(font
					(size 1.27 1.27)
				)
			)
		)
		(duplicate_pad_numbers_are_jumpers no)
		(fp_line
			(start 0.7874 0.4064)
			(end -0.7874 0.4064)
			(stroke
				(width 0.1524)
				(type default)
			)
			(layer "F.SilkS")
		)
		(fp_line
			(start 0.7874 -0.4064)
			(end 0.7874 0.4064)
			(stroke
				(width 0.1524)
				(type default)
			)
			(layer "F.SilkS")
		)
		(fp_line
			(start -0.7874 0.4064)
			(end -0.7874 -0.4064)
			(stroke
				(width 0.1524)
				(type default)
			)
			(layer "F.SilkS")
		)
		(fp_line
			(start -0.7874 -0.4064)
			(end 0.7874 -0.4064)
			(stroke
				(width 0.1524)
				(type default)
			)
			(layer "F.SilkS")
		)
		(fp_line
			(start 0.67945 0.3048)
			(end 0.120396 0.3048)
			(stroke
				(width 0.1)
				(type default)
			)
			(layer "F.Fab")
		)
		(fp_line
			(start 0.67945 -0.3048)
			(end 0.67945 0.3048)
			(stroke
				(width 0.1)
				(type default)
			)
			(layer "F.Fab")
		)
		(fp_line
			(start 0.12065 -0.2794)
			(end 0.12065 -0.3048)
			(stroke
				(width 0.1)
				(type default)
			)
			(layer "F.Fab")
		)
		(fp_line
			(start 0.12065 -0.3048)
			(end 0.67945 -0.3048)
			(stroke
				(width 0.1)
				(type default)
			)
			(layer "F.Fab")
		)
		(fp_line
			(start 0.120396 0.3048)
			(end 0.120396 0.2794)
			(stroke
				(width 0.1)
				(type default)
			)
			(layer "F.Fab")
		)
		(fp_line
			(start 0.120396 0.2794)
			(end -0.12065 0.2794)
			(stroke
				(width 0.1)
				(type default)
			)
			(layer "F.Fab")
		)
		(fp_line
			(start -0.12065 0.3048)
			(end -0.67945 0.3048)
			(stroke
				(width 0.1)
				(type default)
			)
			(layer "F.Fab")
		)
		(fp_line
			(start -0.12065 0.2794)
			(end -0.12065 0.3048)
			(stroke
				(width 0.1)
				(type default)
			)
			(layer "F.Fab")
		)
		(fp_line
			(start -0.12065 -0.2794)
			(end 0.12065 -0.2794)
			(stroke
				(width 0.1)
				(type default)
			)
			(layer "F.Fab")
		)
		(fp_line
			(start -0.12065 -0.305054)
			(end -0.12065 -0.2794)
			(stroke
				(width 0.1)
				(type default)
			)
			(layer "F.Fab")
		)
		(fp_line
			(start -0.67945 0.3048)
			(end -0.67945 -0.305054)
			(stroke
				(width 0.1)
				(type default)
			)
			(layer "F.Fab")
		)
		(fp_line
			(start -0.67945 -0.305054)
			(end -0.12065 -0.305054)
			(stroke
				(width 0.1)
				(type default)
			)
			(layer "F.Fab")
		)
		(pad "1" smd rect
			(at -0.40005 0)
			(size 0.4572 0.508)
			(layers "F.Cu" "F.Mask" "F.Paste")
			(net "USB3_CPU0_BMC_TX_DN")
		)
		(pad "2" smd rect
			(at 0.40005 0)
			(size 0.4572 0.508)
			(layers "F.Cu" "F.Mask" "F.Paste")
			(net "GND")
		)
	)
)
